(kicad_pcb
	(version 20241229)
	(generator "pcbnew")
	(generator_version "9.0")
	(general
		(thickness 1.711)
		(legacy_teardrops no)
	)
	(paper "A4")
	(title_block
		(title "Antmicro Baseboard for Jetson AGX Thor")
		(date "2026-02-18")
		(rev "1.1.0")
		(company "Antmicro Ltd")
		(comment 1 "www.antmicro.com")
		(comment 9 "footprint 710 of 1170 (J18), pads 463-554 of 564")
	)
	(layers
		(0 "F.Cu" signal)
		(4 "In1.Cu" signal)
		(6 "In2.Cu" signal)
		(8 "In3.Cu" signal)
		(10 "In4.Cu" jumper)
		(12 "In5.Cu" signal)
		(14 "In6.Cu" signal)
		(16 "In7.Cu" signal)
		(18 "In8.Cu" signal)
		(2 "B.Cu" signal)
		(9 "F.Adhes" user "F.Adhesive")
		(11 "B.Adhes" user "B.Adhesive")
		(13 "F.Paste" user)
		(15 "B.Paste" user)
		(5 "F.SilkS" user "F.Silkscreen")
		(7 "B.SilkS" user "B.Silkscreen")
		(1 "F.Mask" user)
		(3 "B.Mask" user)
		(17 "Dwgs.User" user "User.Drawings")
		(19 "Cmts.User" user "User.Comments")
		(21 "Eco1.User" user "User.Eco1")
		(23 "Eco2.User" user "User.Eco2")
		(25 "Edge.Cuts" user)
		(27 "Margin" user)
		(31 "F.CrtYd" user "F.Courtyard")
		(29 "B.CrtYd" user "B.Courtyard")
		(35 "F.Fab" user)
		(33 "B.Fab" user)
	)
	(footprint "antmicro-footprints:ASP-208571-01_mounting_holes"
		(locked yes)
		(layer "B.Cu")
		(at 77.680532 103.71 90)
		(property "Reference" "J18"
			(at -25.89 11.119468 270)
			(layer "B.SilkS")
			(effects
				(font
					(size 0.7 0.7)
					(thickness 0.15)
				)
				(justify left bottom mirror)
			)
		)
		(property "Value" "ASP-208571-01_mounting_holes"
			(at -15.05 -10.885 270)
			(layer "B.Fab")
			(effects
				(font
					(size 0.7 0.7)
					(thickness 0.15)
				)
				(justify left bottom mirror)
			)
		)
		(property "Datasheet" "https://suddendocs.samtec.com/prints/asp-208571-01-mkt.pdf"
			(at 0 0 270)
			(layer "B.Fab")
			(hide yes)
			(effects
				(font
					(size 1.27 1.27)
					(thickness 0.15)
				)
				(justify mirror)
			)
		)
		(property "Description" "FMC connector"
			(at 0 0 270)
			(layer "B.Fab")
			(hide yes)
			(effects
				(font
					(size 1.27 1.27)
					(thickness 0.15)
				)
				(justify mirror)
			)
		)
		(property "MPN" "ASP-208571-01"
			(at 0 0 90)
			(unlocked yes)
			(layer "B.Fab")
			(hide yes)
			(effects
				(font
					(size 1 1)
					(thickness 0.15)
				)
				(justify mirror)
			)
		)
		(property "Manufacturer" "Samtec"
			(at 0 0 90)
			(unlocked yes)
			(layer "B.Fab")
			(hide yes)
			(effects
				(font
					(size 1 1)
					(thickness 0.15)
				)
				(justify mirror)
			)
		)
		(property "Author" "Antmicro"
			(at 0 0 90)
			(unlocked yes)
			(layer "B.Fab")
			(hide yes)
			(effects
				(font
					(size 1 1)
					(thickness 0.15)
				)
				(justify mirror)
			)
		)
		(property "License" "Apache-2.0"
			(at 0 0 90)
			(unlocked yes)
			(layer "B.Fab")
			(hide yes)
			(effects
				(font
					(size 1 1)
					(thickness 0.15)
				)
				(justify mirror)
			)
		)
		(sheetname "/Expansion connector/")
		(sheetfile "expansion_connector.kicad_sch")
		(attr smd)
		(pad "M19" smd circle
			(at 1.905 -8.255 90)
			(size 0.64 0.64)
			(layers "B.Cu" "B.Mask")
			(net 1347 "unconnected-(J18-PadM19)")
			(pinfunction "M19")
			(pintype "passive+no_connect")
		)
		(pad "M20" smd circle
			(at 0.635 -8.255 90)
			(size 0.64 0.64)
			(layers "B.Cu" "B.Mask")
			(net 1 "GND")
			(pinfunction "M20")
			(pintype "passive")
		)
		(pad "M21" smd circle
			(at -0.635 -8.255 90)
			(size 0.64 0.64)
			(layers "B.Cu" "B.Mask")
			(net 1 "GND")
			(pinfunction "M21")
			(pintype "passive")
		)
		(pad "M22" smd circle
			(at -1.905 -8.255 90)
			(size 0.64 0.64)
			(layers "B.Cu" "B.Mask")
			(net 1349 "unconnected-(J18-PadM22)")
			(pinfunction "M22")
			(pintype "passive+no_connect")
		)
		(pad "M23" smd circle
			(at -3.175 -8.255 90)
			(size 0.64 0.64)
			(layers "B.Cu" "B.Mask")
			(net 1358 "unconnected-(J18-PadM23)")
			(pinfunction "M23")
			(pintype "passive+no_connect")
		)
		(pad "M24" smd circle
			(at -4.445 -8.255 90)
			(size 0.64 0.64)
			(layers "B.Cu" "B.Mask")
			(net 1 "GND")
			(pinfunction "M24")
			(pintype "passive")
		)
		(pad "M25" smd circle
			(at -5.715 -8.255 90)
			(size 0.64 0.64)
			(layers "B.Cu" "B.Mask")
			(net 1 "GND")
			(pinfunction "M25")
			(pintype "passive")
		)
		(pad "M26" smd circle
			(at -6.985 -8.255 90)
			(size 0.64 0.64)
			(layers "B.Cu" "B.Mask")
			(net 1365 "unconnected-(J18-PadM26)")
			(pinfunction "M26")
			(pintype "passive+no_connect")
		)
		(pad "M27" smd circle
			(at -8.255 -8.255 90)
			(size 0.64 0.64)
			(layers "B.Cu" "B.Mask")
			(net 1364 "unconnected-(J18-PadM27)")
			(pinfunction "M27")
			(pintype "passive+no_connect")
		)
		(pad "M28" smd circle
			(at -9.525 -8.255 90)
			(size 0.64 0.64)
			(layers "B.Cu" "B.Mask")
			(net 1 "GND")
			(pinfunction "M28")
			(pintype "passive")
		)
		(pad "M29" smd circle
			(at -10.795 -8.255 90)
			(size 0.64 0.64)
			(layers "B.Cu" "B.Mask")
			(net 1 "GND")
			(pinfunction "M29")
			(pintype "passive")
		)
		(pad "M30" smd circle
			(at -12.065 -8.255 90)
			(size 0.64 0.64)
			(layers "B.Cu" "B.Mask")
			(net 1363 "unconnected-(J18-PadM30)")
			(pinfunction "M30")
			(pintype "passive+no_connect")
		)
		(pad "M31" smd circle
			(at -13.335 -8.255 90)
			(size 0.64 0.64)
			(layers "B.Cu" "B.Mask")
			(net 1353 "unconnected-(J18-PadM31)")
			(pinfunction "M31")
			(pintype "passive+no_connect")
		)
		(pad "M32" smd circle
			(at -14.605 -8.255 90)
			(size 0.64 0.64)
			(layers "B.Cu" "B.Mask")
			(net 1 "GND")
			(pinfunction "M32")
			(pintype "passive")
		)
		(pad "M33" smd circle
			(at -15.875 -8.255 90)
			(size 0.64 0.64)
			(layers "B.Cu" "B.Mask")
			(net 1 "GND")
			(pinfunction "M33")
			(pintype "passive")
		)
		(pad "M34" smd circle
			(at -17.145 -8.255 90)
			(size 0.64 0.64)
			(layers "B.Cu" "B.Mask")
			(net 1348 "unconnected-(J18-PadM34)")
			(pinfunction "M34")
			(pintype "passive+no_connect")
		)
		(pad "M35" smd circle
			(at -18.415 -8.255 90)
			(size 0.64 0.64)
			(layers "B.Cu" "B.Mask")
			(net 1354 "unconnected-(J18-PadM35)")
			(pinfunction "M35")
			(pintype "passive+no_connect")
		)
		(pad "M36" smd circle
			(at -19.685 -8.255 90)
			(size 0.64 0.64)
			(layers "B.Cu" "B.Mask")
			(net 1 "GND")
			(pinfunction "M36")
			(pintype "passive")
		)
		(pad "M37" smd circle
			(at -20.955 -8.255 90)
			(size 0.64 0.64)
			(layers "B.Cu" "B.Mask")
			(net 1 "GND")
			(pinfunction "M37")
			(pintype "passive")
		)
		(pad "M38" smd circle
			(at -22.225 -8.255 90)
			(size 0.64 0.64)
			(layers "B.Cu" "B.Mask")
			(net 1355 "unconnected-(J18-PadM38)")
			(pinfunction "M38")
			(pintype "passive+no_connect")
		)
		(pad "M39" smd circle
			(at -23.495 -8.255 90)
			(size 0.64 0.64)
			(layers "B.Cu" "B.Mask")
			(net 1357 "unconnected-(J18-PadM39)")
			(pinfunction "M39")
			(pintype "passive+no_connect")
		)
		(pad "M40" smd circle
			(at -24.765 -8.255 90)
			(size 0.64 0.64)
			(layers "B.Cu" "B.Mask")
			(net 1 "GND")
			(pinfunction "M40")
			(pintype "passive")
		)
		(pad "Y01" smd circle
			(at 24.765 8.255 90)
			(size 0.64 0.64)
			(layers "B.Cu" "B.Mask")
			(net 1 "GND")
			(pinfunction "Y01")
			(pintype "passive")
		)
		(pad "Y02" smd circle
			(at 23.495 8.255 90)
			(size 0.64 0.64)
			(layers "B.Cu" "B.Mask")
			(net 350 "unconnected-(J18-PadY02)")
			(pinfunction "Y02")
			(pintype "passive+no_connect")
		)
		(pad "Y03" smd circle
			(at 22.225 8.255 90)
			(size 0.64 0.64)
			(layers "B.Cu" "B.Mask")
			(net 359 "unconnected-(J18-PadY03)")
			(pinfunction "Y03")
			(pintype "passive+no_connect")
		)
		(pad "Y04" smd circle
			(at 20.955 8.255 90)
			(size 0.64 0.64)
			(layers "B.Cu" "B.Mask")
			(net 1 "GND")
			(pinfunction "Y04")
			(pintype "passive")
		)
		(pad "Y05" smd circle
			(at 19.685 8.255 90)
			(size 0.64 0.64)
			(layers "B.Cu" "B.Mask")
			(net 1 "GND")
			(pinfunction "Y05")
			(pintype "passive")
		)
		(pad "Y06" smd circle
			(at 18.415 8.255 90)
			(size 0.64 0.64)
			(layers "B.Cu" "B.Mask")
			(net 325 "unconnected-(J18-PadY06)")
			(pinfunction "Y06")
			(pintype "passive+no_connect")
		)
		(pad "Y07" smd circle
			(at 17.145 8.255 90)
			(size 0.64 0.64)
			(layers "B.Cu" "B.Mask")
			(net 398 "unconnected-(J18-PadY07)")
			(pinfunction "Y07")
			(pintype "passive+no_connect")
		)
		(pad "Y08" smd circle
			(at 15.875 8.255 90)
			(size 0.64 0.64)
			(layers "B.Cu" "B.Mask")
			(net 1 "GND")
			(pinfunction "Y08")
			(pintype "passive")
		)
		(pad "Y09" smd circle
			(at 14.605 8.255 90)
			(size 0.64 0.64)
			(layers "B.Cu" "B.Mask")
			(net 1 "GND")
			(pinfunction "Y09")
			(pintype "passive")
		)
		(pad "Y10" smd circle
			(at 13.335 8.255 90)
			(size 0.64 0.64)
			(layers "B.Cu" "B.Mask")
			(net 729 "/Expansion connector/DP1.AUX+")
			(pinfunction "Y10")
			(pintype "passive")
		)
		(pad "Y11" smd circle
			(at 12.065 8.255 90)
			(size 0.64 0.64)
			(layers "B.Cu" "B.Mask")
			(net 738 "/Expansion connector/DP1.AUX-")
			(pinfunction "Y11")
			(pintype "passive")
		)
		(pad "Y12" smd circle
			(at 10.795 8.255 90)
			(size 0.64 0.64)
			(layers "B.Cu" "B.Mask")
			(net 1 "GND")
			(pinfunction "Y12")
			(pintype "passive")
		)
		(pad "Y13" smd circle
			(at 9.525 8.255 90)
			(size 0.64 0.64)
			(layers "B.Cu" "B.Mask")
			(net 1 "GND")
			(pinfunction "Y13")
			(pintype "passive")
		)
		(pad "Y14" smd circle
			(at 8.255 8.255 90)
			(size 0.64 0.64)
			(layers "B.Cu" "B.Mask")
			(net 707 "/Expansion connector/DP1.TX0+")
			(pinfunction "Y14")
			(pintype "passive")
		)
		(pad "Y15" smd circle
			(at 6.985 8.255 90)
			(size 0.64 0.64)
			(layers "B.Cu" "B.Mask")
			(net 603 "/Expansion connector/DP1.TX0-")
			(pinfunction "Y15")
			(pintype "passive")
		)
		(pad "Y16" smd circle
			(at 5.715 8.255 90)
			(size 0.64 0.64)
			(layers "B.Cu" "B.Mask")
			(net 1 "GND")
			(pinfunction "Y16")
			(pintype "passive")
		)
		(pad "Y17" smd circle
			(at 4.445 8.255 90)
			(size 0.64 0.64)
			(layers "B.Cu" "B.Mask")
			(net 1 "GND")
			(pinfunction "Y17")
			(pintype "passive")
		)
		(pad "Y18" smd circle
			(at 3.175 8.255 90)
			(size 0.64 0.64)
			(layers "B.Cu" "B.Mask")
			(net 771 "/Expansion connector/DP1.TX1+")
			(pinfunction "Y18")
			(pintype "passive")
		)
		(pad "Y19" smd circle
			(at 1.905 8.255 90)
			(size 0.64 0.64)
			(layers "B.Cu" "B.Mask")
			(net 713 "/Expansion connector/DP1.TX1-")
			(pinfunction "Y19")
			(pintype "passive")
		)
		(pad "Y20" smd circle
			(at 0.635 8.255 90)
			(size 0.64 0.64)
			(layers "B.Cu" "B.Mask")
			(net 1 "GND")
			(pinfunction "Y20")
			(pintype "passive")
		)
		(pad "Y21" smd circle
			(at -0.635 8.255 90)
			(size 0.64 0.64)
			(layers "B.Cu" "B.Mask")
			(net 1 "GND")
			(pinfunction "Y21")
			(pintype "passive")
		)
		(pad "Y22" smd circle
			(at -1.905 8.255 90)
			(size 0.64 0.64)
			(layers "B.Cu" "B.Mask")
			(net 732 "/Expansion connector/PCIe_{C3x2}.CLK-")
			(pinfunction "Y22")
			(pintype "passive")
		)
		(pad "Y23" smd circle
			(at -3.175 8.255 90)
			(size 0.64 0.64)
			(layers "B.Cu" "B.Mask")
			(net 699 "/Expansion connector/PCIe_{C3x2}.CLK+")
			(pinfunction "Y23")
			(pintype "passive")
		)
		(pad "Y24" smd circle
			(at -4.445 8.255 90)
			(size 0.64 0.64)
			(layers "B.Cu" "B.Mask")
			(net 1 "GND")
			(pinfunction "Y24")
			(pintype "passive")
		)
		(pad "Y25" smd circle
			(at -5.715 8.255 90)
			(size 0.64 0.64)
			(layers "B.Cu" "B.Mask")
			(net 1 "GND")
			(pinfunction "Y25")
			(pintype "passive")
		)
		(pad "Y26" smd circle
			(at -6.985 8.255 90)
			(size 0.64 0.64)
			(layers "B.Cu" "B.Mask")
			(net 797 "/Expansion connector/PCIe_{C3x2}.RX0+")
			(pinfunction "Y26")
			(pintype "passive")
		)
		(pad "Y27" smd circle
			(at -8.255 8.255 90)
			(size 0.64 0.64)
			(layers "B.Cu" "B.Mask")
			(net 752 "/Expansion connector/PCIe_{C3x2}.RX0-")
			(pinfunction "Y27")
			(pintype "passive")
		)
		(pad "Y28" smd circle
			(at -9.525 8.255 90)
			(size 0.64 0.64)
			(layers "B.Cu" "B.Mask")
			(net 1 "GND")
			(pinfunction "Y28")
			(pintype "passive")
		)
		(pad "Y29" smd circle
			(at -10.795 8.255 90)
			(size 0.64 0.64)
			(layers "B.Cu" "B.Mask")
			(net 1 "GND")
			(pinfunction "Y29")
			(pintype "passive")
		)
		(pad "Y30" smd circle
			(at -12.065 8.255 90)
			(size 0.64 0.64)
			(layers "B.Cu" "B.Mask")
			(net 782 "/Expansion connector/PCIe_{C3x2}.RX1+")
			(pinfunction "Y30")
			(pintype "passive")
		)
		(pad "Y31" smd circle
			(at -13.335 8.255 90)
			(size 0.64 0.64)
			(layers "B.Cu" "B.Mask")
			(net 722 "/Expansion connector/PCIe_{C3x2}.RX1-")
			(pinfunction "Y31")
			(pintype "passive")
		)
		(pad "Y32" smd circle
			(at -14.605 8.255 90)
			(size 0.64 0.64)
			(layers "B.Cu" "B.Mask")
			(net 1 "GND")
			(pinfunction "Y32")
			(pintype "passive")
		)
		(pad "Y33" smd circle
			(at -15.875 8.255 90)
			(size 0.64 0.64)
			(layers "B.Cu" "B.Mask")
			(net 1 "GND")
			(pinfunction "Y33")
			(pintype "passive")
		)
		(pad "Y34" smd circle
			(at -17.145 8.255 90)
			(size 0.64 0.64)
			(layers "B.Cu" "B.Mask")
			(net 518 "/Expansion connector/PET0_C3_N")
			(pinfunction "Y34")
			(pintype "passive")
		)
		(pad "Y35" smd circle
			(at -18.415 8.255 90)
			(size 0.64 0.64)
			(layers "B.Cu" "B.Mask")
			(net 452 "/Expansion connector/PET0_C3_P")
			(pinfunction "Y35")
			(pintype "passive")
		)
		(pad "Y36" smd circle
			(at -19.685 8.255 90)
			(size 0.64 0.64)
			(layers "B.Cu" "B.Mask")
			(net 1 "GND")
			(pinfunction "Y36")
			(pintype "passive")
		)
		(pad "Y37" smd circle
			(at -20.955 8.255 90)
			(size 0.64 0.64)
			(layers "B.Cu" "B.Mask")
			(net 1 "GND")
			(pinfunction "Y37")
			(pintype "passive")
		)
		(pad "Y38" smd circle
			(at -22.225 8.255 90)
			(size 0.64 0.64)
			(layers "B.Cu" "B.Mask")
			(net 475 "/Expansion connector/PET1_C3_P")
			(pinfunction "Y38")
			(pintype "passive")
		)
		(pad "Y39" smd circle
			(at -23.495 8.255 90)
			(size 0.64 0.64)
			(layers "B.Cu" "B.Mask")
			(net 520 "/Expansion connector/PET1_C3_N")
			(pinfunction "Y39")
			(pintype "passive")
		)
		(pad "Y40" smd circle
			(at -24.765 8.255 90)
			(size 0.64 0.64)
			(layers "B.Cu" "B.Mask")
			(net 1 "GND")
			(pinfunction "Y40")
			(pintype "passive")
		)
		(pad "Z01" smd circle
			(at 24.765 6.985 90)
			(size 0.64 0.64)
			(layers "B.Cu" "B.Mask")
			(net 341 "/Expansion connector/FMC_PRESENT")
			(pinfunction "Z01")
			(pintype "passive")
		)
		(pad "Z02" smd circle
			(at 23.495 6.985 90)
			(size 0.64 0.64)
			(layers "B.Cu" "B.Mask")
			(net 1 "GND")
			(pinfunction "Z02")
			(pintype "passive")
		)
		(pad "Z03" smd circle
			(at 22.225 6.985 90)
			(size 0.64 0.64)
			(layers "B.Cu" "B.Mask")
			(net 1 "GND")
			(pinfunction "Z03")
			(pintype "passive")
		)
		(pad "Z04" smd circle
			(at 20.955 6.985 90)
			(size 0.64 0.64)
			(layers "B.Cu" "B.Mask")
			(net 468 "unconnected-(J18-PadZ04)")
			(pinfunction "Z04")
			(pintype "passive+no_connect")
		)
		(pad "Z05" smd circle
			(at 19.685 6.985 90)
			(size 0.64 0.64)
			(layers "B.Cu" "B.Mask")
			(net 469 "unconnected-(J18-PadZ05)")
			(pinfunction "Z05")
			(pintype "passive+no_connect")
		)
		(pad "Z06" smd circle
			(at 18.415 6.985 90)
			(size 0.64 0.64)
			(layers "B.Cu" "B.Mask")
			(net 1 "GND")
			(pinfunction "Z06")
			(pintype "passive")
		)
		(pad "Z07" smd circle
			(at 17.145 6.985 90)
			(size 0.64 0.64)
			(layers "B.Cu" "B.Mask")
			(net 1 "GND")
			(pinfunction "Z07")
			(pintype "passive")
		)
		(pad "Z08" smd circle
			(at 15.875 6.985 90)
			(size 0.64 0.64)
			(layers "B.Cu" "B.Mask")
			(net 425 "unconnected-(J18-PadZ08)")
			(pinfunction "Z08")
			(pintype "passive+no_connect")
		)
		(pad "Z09" smd circle
			(at 14.605 6.985 90)
			(size 0.64 0.64)
			(layers "B.Cu" "B.Mask")
			(net 619 "unconnected-(J18-PadZ09)")
			(pinfunction "Z09")
			(pintype "passive+no_connect")
		)
		(pad "Z10" smd circle
			(at 13.335 6.985 90)
			(size 0.64 0.64)
			(layers "B.Cu" "B.Mask")
			(net 1 "GND")
			(pinfunction "Z10")
			(pintype "passive")
		)
		(pad "Z11" smd circle
			(at 12.065 6.985 90)
			(size 0.64 0.64)
			(layers "B.Cu" "B.Mask")
			(net 1 "GND")
			(pinfunction "Z11")
			(pintype "passive")
		)
		(pad "Z12" smd circle
			(at 10.795 6.985 90)
			(size 0.64 0.64)
			(layers "B.Cu" "B.Mask")
			(net 570 "/Expansion connector/DP1.TX2+")
			(pinfunction "Z12")
			(pintype "passive")
		)
		(pad "Z13" smd circle
			(at 9.525 6.985 90)
			(size 0.64 0.64)
			(layers "B.Cu" "B.Mask")
			(net 733 "/Expansion connector/DP1.TX2-")
			(pinfunction "Z13")
			(pintype "passive")
		)
		(pad "Z14" smd circle
			(at 8.255 6.985 90)
			(size 0.64 0.64)
			(layers "B.Cu" "B.Mask")
			(net 1 "GND")
			(pinfunction "Z14")
			(pintype "passive")
		)
		(pad "Z15" smd circle
			(at 6.985 6.985 90)
			(size 0.64 0.64)
			(layers "B.Cu" "B.Mask")
			(net 1 "GND")
			(pinfunction "Z15")
			(pintype "passive")
		)
		(pad "Z16" smd circle
			(at 5.715 6.985 90)
			(size 0.64 0.64)
			(layers "B.Cu" "B.Mask")
			(net 794 "/Expansion connector/DP1.TX3+")
			(pinfunction "Z16")
			(pintype "passive")
		)
		(pad "Z17" smd circle
			(at 4.445 6.985 90)
			(size 0.64 0.64)
			(layers "B.Cu" "B.Mask")
			(net 682 "/Expansion connector/DP1.TX3-")
			(pinfunction "Z17")
			(pintype "passive")
		)
		(pad "Z18" smd circle
			(at 3.175 6.985 90)
			(size 0.64 0.64)
			(layers "B.Cu" "B.Mask")
			(net 1 "GND")
			(pinfunction "Z18")
			(pintype "passive")
		)
		(pad "Z19" smd circle
			(at 1.905 6.985 90)
			(size 0.64 0.64)
			(layers "B.Cu" "B.Mask")
			(net 1 "GND")
			(pinfunction "Z19")
			(pintype "passive")
		)
		(pad "Z20" smd circle
			(at 0.635 6.985 90)
			(size 0.64 0.64)
			(layers "B.Cu" "B.Mask")
			(net 1137 "unconnected-(J18-PadZ20)")
			(pinfunction "Z20")
			(pintype "passive+no_connect")
		)
		(pad "Z21" smd circle
			(at -0.635 6.985 90)
			(size 0.64 0.64)
			(layers "B.Cu" "B.Mask")
			(net 1136 "unconnected-(J18-PadZ21)")
			(pinfunction "Z21")
			(pintype "passive+no_connect")
		)
		(pad "Z22" smd circle
			(at -1.905 6.985 90)
			(size 0.64 0.64)
			(layers "B.Cu" "B.Mask")
			(net 1 "GND")
			(pinfunction "Z22")
			(pintype "passive")
		)
		(pad "Z23" smd circle
			(at -3.175 6.985 90)
			(size 0.64 0.64)
			(layers "B.Cu" "B.Mask")
			(net 1 "GND")
			(pinfunction "Z23")
			(pintype "passive")
		)
		(pad "Z24" smd circle
			(at -4.445 6.985 90)
			(size 0.64 0.64)
			(layers "B.Cu" "B.Mask")
			(net 562 "unconnected-(J18-PadZ24)")
			(pinfunction "Z24")
			(pintype "passive+no_connect")
		)
		(pad "Z25" smd circle
			(at -5.715 6.985 90)
			(size 0.64 0.64)
			(layers "B.Cu" "B.Mask")
			(net 576 "unconnected-(J18-PadZ25)")
			(pinfunction "Z25")
			(pintype "passive+no_connect")
		)
		(pad "Z26" smd circle
			(at -6.985 6.985 90)
			(size 0.64 0.64)
			(layers "B.Cu" "B.Mask")
			(net 1 "GND")
			(pinfunction "Z26")
			(pintype "passive")
		)
		(pad "Z27" smd circle
			(at -8.255 6.985 90)
			(size 0.64 0.64)
			(layers "B.Cu" "B.Mask")
			(net 1 "GND")
			(pinfunction "Z27")
			(pintype "passive")
		)
		(pad "Z28" smd circle
			(at -9.525 6.985 90)
			(size 0.64 0.64)
			(layers "B.Cu" "B.Mask")
			(net 728 "/Expansion connector/PER0_C2_P")
			(pinfunction "Z28")
			(pintype "passive")
		)
		(pad "Z29" smd circle
			(at -10.795 6.985 90)
			(size 0.64 0.64)
			(layers "B.Cu" "B.Mask")
			(net 471 "/Expansion connector/PER0_C2_N")
			(pinfunction "Z29")
			(pintype "passive")
		)
		(pad "Z30" smd circle
			(at -12.065 6.985 90)
			(size 0.64 0.64)
			(layers "B.Cu" "B.Mask")
			(net 1 "GND")
			(pinfunction "Z30")
			(pintype "passive")
		)
	)
)
